FILE_TYPE=LIBRARY_PARTS;
TIME=' Created/Modified on Wed Jun 23 16:24:53 2010' ;
primitive 'SN74LVC1G14DCKR';
  pin
    'A':
      PIN_NUMBER='(2)';
      INPUT_LOAD='(-0.01,0.01)';
    'Y':
      PIN_NUMBER='(4)';
      OUTPUT_LOAD='(1.0,*)';
      OUTPUT_TYPE='(OC,AND)';
    'NC':
      PIN_NUMBER='(1)';
      INPUT_LOAD='(-0.01,0.01)';
      OUTPUT_LOAD='(1.0,-1.0)';
      OUTPUT_TYPE='(TS,TS)';
    'VCC':
      PIN_NUMBER='(5)';
      PINUSE='POWER';
    'GND':
      PIN_NUMBER='(3)';
      PINUSE='POWER';
  end_pin;
  body
    CLASS='IC';
    PART_NAME='SN74LVC1G14DCKR';
    PHYS_DES_PREFIX='U';
  end_body;
end_primitive;
END.
